FILE_TYPE=LIBRARY_PARTS;
primitive 'ADM1278','ADM1278_SM';
  pin
    'ADR1':
      PIN_NUMBER='(7)';
      PIN_TYPE='ANALOG';
      NO_LOAD_CHECK='Both';
      NO_IO_CHECK='Both';
      NO_ASSERT_CHECK='TRUE';
      NO_DIR_CHECK='TRUE';
      ALLOW_CONNECT='TRUE';
    'ADR2':
      PIN_NUMBER='(8)';
      PIN_TYPE='ANALOG';
      NO_LOAD_CHECK='Both';
      NO_IO_CHECK='Both';
      NO_ASSERT_CHECK='TRUE';
      NO_DIR_CHECK='TRUE';
      ALLOW_CONNECT='TRUE';
    'CSOUT':
      PIN_NUMBER='(19)';
      OUTPUT_LOAD='(1.0,-1.0)';
    'ENABLE':
      PIN_NUMBER='(12)';
      INPUT_LOAD='(-0.01,0.01)';
    'EP':
      PIN_NUMBER='(33)';
      PINUSE='GROUND';
      NO_LOAD_CHECK='Both';
      NO_IO_CHECK='Both';
      NO_ASSERT_CHECK='TRUE';
      NO_DIR_CHECK='TRUE';
      ALLOW_CONNECT='TRUE';
    'FAULT_N':
      PIN_NUMBER='(6)';
      PIN_TYPE='ANALOG';
      NO_LOAD_CHECK='Both';
      NO_IO_CHECK='Both';
      NO_ASSERT_CHECK='TRUE';
      NO_DIR_CHECK='TRUE';
      ALLOW_CONNECT='TRUE';
    'GATE':
      PIN_NUMBER='(24)';
      OUTPUT_LOAD='(1.0,-1.0)';
    'GND':
      PIN_NUMBER='(22)';
      PINUSE='GROUND';
      NO_LOAD_CHECK='Both';
      NO_IO_CHECK='Both';
      NO_ASSERT_CHECK='TRUE';
      NO_DIR_CHECK='TRUE';
      ALLOW_CONNECT='TRUE';
    'GPO1_ALERT1_N_CONV':
      PIN_NUMBER='(13)';
      BIDIRECTIONAL='TRUE';
      INPUT_LOAD='(-0.01,0.01)';
      OUTPUT_LOAD='(1.0,-1.0)';
    'GPO2_ALERT2_N':
      PIN_NUMBER='(14)';
      BIDIRECTIONAL='TRUE';
      INPUT_LOAD='(-0.01,0.01)';
      OUTPUT_LOAD='(1.0,-1.0)';
    'HSN':
      PIN_NUMBER='(27)';
      INPUT_LOAD='(-0.01,0.01)';
    'HSP':
      PIN_NUMBER='(28)';
      INPUT_LOAD='(-0.01,0.01)';
    'ISET':
      PIN_NUMBER='(3)';
      INPUT_LOAD='(-0.01,0.01)';
    'ISTART':
      PIN_NUMBER='(4)';
      INPUT_LOAD='(-0.01,0.01)';
    'MCLK':
      PIN_NUMBER='(10)';
      OUTPUT_LOAD='(1.0,-1.0)';
    'MDAT':
      PIN_NUMBER='(11)';
      OUTPUT_LOAD='(1.0,-1.0)';
    'MON':
      PIN_NUMBER='(26)';
      INPUT_LOAD='(-0.01,0.01)';
    'MOP':
      PIN_NUMBER='(29)';
      INPUT_LOAD='(-0.01,0.01)';
    'OV':
      PIN_NUMBER='(32)';
      INPUT_LOAD='(-0.01,0.01)';
    'PGND':
      PIN_NUMBER='(23)';
      PINUSE='GROUND';
      NO_LOAD_CHECK='Both';
      NO_IO_CHECK='Both';
      NO_ASSERT_CHECK='TRUE';
      NO_DIR_CHECK='TRUE';
      ALLOW_CONNECT='TRUE';
    'PSET':
      PIN_NUMBER='(1)';
      INPUT_LOAD='(-0.01,0.01)';
    'PWGIN':
      PIN_NUMBER='(21)';
      INPUT_LOAD='(-0.01,0.01)';
    'PWRGD':
      PIN_NUMBER='(18)';
      PIN_TYPE='ANALOG';
      NO_LOAD_CHECK='Both';
      NO_IO_CHECK='Both';
      NO_ASSERT_CHECK='TRUE';
      NO_DIR_CHECK='TRUE';
      ALLOW_CONNECT='TRUE';
    'RETRY_N':
      PIN_NUMBER='(17)';
      PIN_TYPE='ANALOG';
      NO_LOAD_CHECK='Both';
      NO_IO_CHECK='Both';
      NO_ASSERT_CHECK='TRUE';
      NO_DIR_CHECK='TRUE';
      ALLOW_CONNECT='TRUE';
    'SCL':
      PIN_NUMBER='(16)';
      INPUT_LOAD='(-0.01,0.01)';
    'SDA':
      PIN_NUMBER='(15)';
      BIDIRECTIONAL='TRUE';
      INPUT_LOAD='(-0.01,0.01)';
      OUTPUT_LOAD='(1.0,-1.0)';
    'SPISS_N':
      PIN_NUMBER='(9)';
      PIN_TYPE='ANALOG';
      NO_LOAD_CHECK='Both';
      NO_IO_CHECK='Both';
      NO_ASSERT_CHECK='TRUE';
      NO_DIR_CHECK='TRUE';
      ALLOW_CONNECT='TRUE';
    'TEMP':
      PIN_NUMBER='(25)';
      INPUT_LOAD='(-0.01,0.01)';
    'TIMER':
      PIN_NUMBER='(5)';
      PIN_TYPE='ANALOG';
      NO_LOAD_CHECK='Both';
      NO_IO_CHECK='Both';
      NO_ASSERT_CHECK='TRUE';
      NO_DIR_CHECK='TRUE';
      ALLOW_CONNECT='TRUE';
    'UV':
      PIN_NUMBER='(31)';
      INPUT_LOAD='(-0.01,0.01)';
    'VCAP':
      PIN_NUMBER='(2)';
      INPUT_LOAD='(-0.01,0.01)';
    'VCC':
      PIN_NUMBER='(30)';
      PINUSE='POWER';
      NO_LOAD_CHECK='Both';
      NO_IO_CHECK='Both';
      NO_ASSERT_CHECK='TRUE';
      NO_DIR_CHECK='TRUE';
      ALLOW_CONNECT='TRUE';
    'VOUT':
      PIN_NUMBER='(20)';
      OUTPUT_LOAD='(1.0,-1.0)';
  end_pin;
  body
    PART_NAME='ADM1278';
    PHYS_DES_PREFIX='EU';
  end_body;
end_primitive;

END.
